FILE_TYPE = MULTI_PHYS_TABLE;
PART 'SCONN60_C21100002'
{========================================================================================}
:PACK_TYPE | MATERIAL | PART_NUMBER     = EnvComp | PART_NUMBER  |JEDEC_TYPE          |CLASS  |DESCRIPTION  |HEIGHT     |COMPONENT_TYPE  | LPID   | SPEED_URL | Status |RPL| AML | Bus_Unit | Days ;
{========================================================================================}
'SMLF'     | 'CONN'   | 'C21100-002'(!) = 'YES;YES;YES;UNK;ok;CIP' | 'C21100-002' |'SCONN60_C21100002' | 'IO'  | 'SAMTEC 60' | '.120 IN' |   'SMTCONN'    | ''     | 'http://speed.intel.com:8081/speed/module/pdm/item/pdm_item_detail_direct.asp?item_cde=C21100-002&item_rev=01&url_param=unused' | 'Unqual' | 'NO' | '1' | 'SMO_BOARDS' | '56' 
'SMLF'     | 'EMPTY'  | 'C21100-002'(!) = 'YES;YES;YES;UNK;ok;CIP' | 'C21100-002' |'SCONN60_C21100002' | 'IO'  | 'SAMTEC 60' | '.120 IN' |   'SMTCONN'    | ''     | 'http://speed.intel.com:8081/speed/module/pdm/item/pdm_item_detail_direct.asp?item_cde=C21100-002&item_rev=01&url_param=unused' | 'Unqual' | 'NO' | '1' | 'SMO_BOARDS' | '56' 
'SMT'      | 'CONN'   | 'C21100-002'(!) = 'YES;YES;YES;UNK;ok;CIP' | 'C21100-002' |'SCONN60_C21100002A' | 'IO'  | 'CONN,MISC,60 P,.5MM,SOCKET' | '0.120 IN' |   'SMTCONN'    | ''   | 'http://speed.intel.com:8081/speed/module/pdm/item/pdm_item_detail_direct.asp?item_cde=C21100-002&item_rev=01&url_param=unused' | 'Unqual' | 'NO' | '1' | 'SMO_BOARDS' | '56' 
'SMT'      | 'EMPTY'  | 'C21100-002'(!) = 'YES;YES;YES;UNK;ok;CIP' | 'C21100-002' |'SCONN60_C21100002A' | 'IO'  | 'CONN,MISC,60 P,.5MM,SOCKET' | '0.120 IN' |   'SMTCONN'    | ''   | 'http://speed.intel.com:8081/speed/module/pdm/item/pdm_item_detail_direct.asp?item_cde=C21100-002&item_rev=01&url_param=unused' | 'Unqual' | 'NO' | '1' | 'SMO_BOARDS' | '56' 
END_PART
END.
